FILE_TYPE = CONNECTIVITY;
{Allegro Design Entry HDL 17.2-2016 S081 (4005846) 1/11/2022}
"PAGE_NUMBER" = 47;
0"NC";
1"M_K_CPU1_SA_DQ<31:0>";
2"M_K_CPU1_SB_DQ<31:0>";
3"M_K_CPU1_SA_CB<7:0>";
4"M_K_CPU1_SB_CB<7:0>";
5"M_K_CPU1_SA_DQS_DP<9:0>";
6"M_K_CPU1_SB_DQS_DP<9:0>";
7"M_K_CPU1_SA_CA<6:0>";
8"M_K_CPU1_SB_CA<6:0>";
9"M_K_CPU1_SA_DQS_DN<9:0>";
10"M_K_CPU1_SB_DQS_DN<9:0>";
11"M_K_CPU1_ALERT_N";
12"TP_M_K_CPU1_SA_TEST39K";
13"M_K_CPU1_ALERT_R_N";
14"M_K_CPU1_CLK_DN<0>";
15"M_K_CPU1_CLK_DP<0>";
16"M_K_CPU1_SA_CS_N<0>";
17"M_K_CPU1_SA_CS_N<1>";
18"M_K_CPU1_SA_RSP<0>";
19"M_K_CPU1_SA_PAR";
20"M_K_CPU1_SB_CS_N<0>";
21"M_K_CPU1_SB_CS_N<1>";
22"M_K_CPU1_SB_RSP<0>";
23"M_K_CPU1_SB_PAR";
24"M_K_CPU1_RESET_N";
25"M_K_CPU1_SB_CA<6>";
26"M_K_CPU1_SA_CA<0>";
27"M_K_CPU1_SA_CA<6>";
28"M_K_CPU1_SB_CA<5>";
29"M_K_CPU1_SA_CA<5>";
30"M_K_CPU1_SB_CA<4>";
31"M_K_CPU1_SA_CA<4>";
32"M_K_CPU1_SB_CA<3>";
33"M_K_CPU1_SB_DQS_DN<9>";
34"M_K_CPU1_SA_CA<3>";
35"M_K_CPU1_SB_CA<2>";
36"M_K_CPU1_SB_DQS_DN<8>";
37"M_K_CPU1_SA_CA<2>";
38"M_K_CPU1_SB_CA<1>";
39"M_K_CPU1_SA_CA<1>";
40"M_K_CPU1_SB_CA<0>";
41"M_K_CPU1_SB_DQS_DP<9>";
42"M_K_CPU1_SB_DQS_DP<8>";
43"M_K_CPU1_SB_DQS_DN<5>";
44"M_K_CPU1_SB_DQS_DN<4>";
45"M_K_CPU1_SA_DQS_DN<9>";
46"M_K_CPU1_SB_DQS_DN<3>";
47"M_K_CPU1_SA_DQS_DN<8>";
48"M_K_CPU1_SB_DQS_DN<2>";
49"M_K_CPU1_SB_DQS_DN<1>";
50"M_K_CPU1_SB_DQS_DN<0>";
51"M_K_CPU1_SB_DQS_DN<7>";
52"M_K_CPU1_SB_DQS_DN<6>";
53"M_K_CPU1_SB_DQS_DP<7>";
54"M_K_CPU1_SB_DQS_DP<6>";
55"M_K_CPU1_SB_DQS_DP<5>";
56"M_K_CPU1_SB_DQS_DP<4>";
57"M_K_CPU1_SB_DQS_DP<3>";
58"M_K_CPU1_SB_DQS_DP<1>";
59"M_K_CPU1_SB_DQS_DP<0>";
60"M_K_CPU1_SA_DQS_DP<9>";
61"M_K_CPU1_SA_DQS_DP<8>";
62"M_K_CPU1_SB_DQS_DP<2>";
63"M_K_CPU1_SA_DQS_DN<7>";
64"M_K_CPU1_SA_DQS_DN<6>";
65"M_K_CPU1_SA_DQS_DN<5>";
66"M_K_CPU1_SA_DQS_DN<4>";
67"M_K_CPU1_SA_DQS_DN<3>";
68"M_K_CPU1_SA_DQS_DN<2>";
69"M_K_CPU1_SA_DQS_DN<1>";
70"M_K_CPU1_SA_DQS_DN<0>";
71"M_K_CPU1_SA_DQS_DP<7>";
72"M_K_CPU1_SA_DQS_DP<6>";
73"M_K_CPU1_SA_DQS_DP<5>";
74"M_K_CPU1_SA_DQS_DP<4>";
75"M_K_CPU1_SA_DQS_DP<3>";
76"M_K_CPU1_SA_DQS_DP<2>";
77"M_K_CPU1_SA_DQS_DP<1>";
78"M_K_CPU1_SA_DQS_DP<0>";
79"M_K_CPU1_SB_CB<7>";
80"M_K_CPU1_SB_CB<6>";
81"M_K_CPU1_SB_CB<5>";
82"M_K_CPU1_SB_CB<4>";
83"M_K_CPU1_SB_CB<3>";
84"M_K_CPU1_SB_CB<2>";
85"M_K_CPU1_SA_CB<7>";
86"M_K_CPU1_SB_CB<1>";
87"M_K_CPU1_SA_CB<6>";
88"M_K_CPU1_SB_CB<0>";
89"M_K_CPU1_SB_DQ<29>";
90"M_K_CPU1_SB_DQ<28>";
91"M_K_CPU1_SB_DQ<27>";
92"M_K_CPU1_SB_DQ<26>";
93"M_K_CPU1_SB_DQ<25>";
94"M_K_CPU1_SB_DQ<24>";
95"M_K_CPU1_SB_DQ<23>";
96"M_K_CPU1_SB_DQ<22>";
97"M_K_CPU1_SB_DQ<21>";
98"M_K_CPU1_SB_DQ<20>";
99"M_K_CPU1_SB_DQ<31>";
100"M_K_CPU1_SA_CB<5>";
101"M_K_CPU1_SB_DQ<30>";
102"M_K_CPU1_SA_CB<4>";
103"M_K_CPU1_SA_CB<3>";
104"M_K_CPU1_SA_CB<2>";
105"M_K_CPU1_SA_CB<1>";
106"M_K_CPU1_SA_CB<0>";
107"M_K_CPU1_SB_DQ<19>";
108"M_K_CPU1_SB_DQ<9>";
109"M_K_CPU1_SB_DQ<18>";
110"M_K_CPU1_SB_DQ<8>";
111"M_K_CPU1_SB_DQ<17>";
112"M_K_CPU1_SB_DQ<7>";
113"M_K_CPU1_SB_DQ<16>";
114"M_K_CPU1_SB_DQ<6>";
115"M_K_CPU1_SB_DQ<15>";
116"M_K_CPU1_SB_DQ<5>";
117"M_K_CPU1_SB_DQ<14>";
118"M_K_CPU1_SB_DQ<4>";
119"M_K_CPU1_SB_DQ<13>";
120"M_K_CPU1_SB_DQ<3>";
121"M_K_CPU1_SB_DQ<12>";
122"M_K_CPU1_SB_DQ<2>";
123"M_K_CPU1_SB_DQ<11>";
124"M_K_CPU1_SB_DQ<1>";
125"M_K_CPU1_SB_DQ<10>";
126"M_K_CPU1_SA_DQ<19>";
127"M_K_CPU1_SA_DQ<18>";
128"M_K_CPU1_SA_DQ<29>";
129"M_K_CPU1_SA_DQ<17>";
130"M_K_CPU1_SA_DQ<28>";
131"M_K_CPU1_SA_DQ<16>";
132"M_K_CPU1_SA_DQ<27>";
133"M_K_CPU1_SA_DQ<15>";
134"M_K_CPU1_SA_DQ<26>";
135"M_K_CPU1_SB_DQ<0>";
136"M_K_CPU1_SA_DQ<25>";
137"M_K_CPU1_SA_DQ<24>";
138"M_K_CPU1_SA_DQ<23>";
139"M_K_CPU1_SA_DQ<22>";
140"M_K_CPU1_SA_DQ<21>";
141"M_K_CPU1_SA_DQ<20>";
142"M_K_CPU1_SA_DQ<31>";
143"M_K_CPU1_SA_DQ<30>";
144"M_K_CPU1_SA_DQ<9>";
145"M_K_CPU1_SA_DQ<8>";
146"M_K_CPU1_SA_DQ<7>";
147"M_K_CPU1_SA_DQ<6>";
148"M_K_CPU1_SA_DQ<5>";
149"M_K_CPU1_SA_DQ<4>";
150"M_K_CPU1_SA_DQ<3>";
151"M_K_CPU1_SA_DQ<2>";
152"M_K_CPU1_SA_DQ<1>";
153"M_K_CPU1_SA_DQ<0>";
154"M_K_CPU1_SA_DQ<14>";
155"M_K_CPU1_SA_DQ<13>";
156"M_K_CPU1_SA_DQ<12>";
157"M_K_CPU1_SA_DQ<11>";
158"M_K_CPU1_SA_DQ<10>";
%"GENOA_SP5"
"36","(-4500,3525)","0","pure_quanta","I159";
;
LOCATION"U26"
$SEC"36"
CDS_SEC"36"
PART_TYPE"SMLF"
MATERIAL"IO"
VALUE"SOCKET6096_13568-001"
PART_NUMBER"DGA^6000030"
CDS_LIB"pure_quanta"
CDS_LMAN_SYM_OUTLINE"-650,2525,650,-2525"
NEEDS_NO_SIZE"TRUE";
"TEST39K"
$PN"BF7"12;
"MKA0_CS_L0"
$PN"AU5"16;
"MKA_CA0"
$PN"AW5"26;
"MKA_DQS_H7"
$PN"AA7"71;
"MKB_DATA9"
$PN"CJ7"108;
"MKB_DATA18"
$PN"CR5"109;
"MKB_DATA29"
$PN"DE7"89;
"MKB_DQS_H1"
$PN"CK6"58;
"MKB_DQS_L5"
$PN"CE7"43;
"MKA_DATA9"
$PN"M7"144;
"MKA_DQS_H6"
$PN"R7"72;
"MKB1_RSP_L"
$PN"BR5"0;
"MKB_DATA8"
$PN"CH6"110;
"MKB_DATA17"
$PN"CR7"111;
"MKB_DATA28"
$PN"DD6"90;
"MKB_DQS_H0"
$PN"CD6"59;
"MKB_DQS_L4"
$PN"BW7"44;
"MKA_DATA8"
$PN"L5"145;
"MKA_DQS_H5"
$PN"J7"73;
"MKA_DQS_L9"
$PN"AM7"45;
"MKB0_RSP_L"
$PN"BP6"22;
"MKB_CHECK7"
$PN"BV7"79;
"MKB_DATA7"
$PN"CH7"112;
"MKB_DATA16"
$PN"CP6"113;
"MKB_DATA27"
$PN"DB7"91;
"MKB_DQS_L3"
$PN"DC5"46;
"MKA_DATA7"
$PN"L7"146;
"MKA_DQS_H4"
$PN"AL5"74;
"MKA_DQS_L8"
$PN"AF7"47;
"MKB_CHECK6"
$PN"BU5"80;
"MKB_DATA6"
$PN"CG5"114;
"MKB_DATA15"
$PN"CP7"115;
"MKB_DATA26"
$PN"DA5"92;
"MKB_DQS_L2"
$PN"CU5"48;
"MKB_PAR"
$PN"BL7"23;
"MKA_DATA6"
$PN"K6"147;
"MKA_DQS_H3"
$PN"AE5"75;
"MKA_DQS_L7"
$PN"Y7"63;
"MKA_PAR"
$PN"BC7"19;
"MKB_CHECK5"
$PN"BU7"81;
"MKB_DATA5"
$PN"CG7"116;
"MKB_DATA14"
$PN"CN5"117;
"MKB_DATA25"
$PN"DA7"93;
"MKB_DQS_L1"
$PN"CL5"49;
"MKA_DATA5"
$PN"K7"148;
"MKA_DATA19"
$PN"W7"126;
"MKA_DQS_H2"
$PN"W5"76;
"MKA_DQS_L6"
$PN"P7"64;
"MKB_CHECK4"
$PN"BT6"82;
"MKB_DATA4"
$PN"CF6"118;
"MKB_DATA13"
$PN"CN7"119;
"MKB_DATA24"
$PN"CY6"94;
"MKB_DQS_L0"
$PN"CE5"50;
"MKA_DATA4"
$PN"J5"149;
"MKA_DATA18"
$PN"V6"127;
"MKA_DATA29"
$PN"AH7"128;
"MKA_DQS_H1"
$PN"N5"77;
"MKA_DQS_L5"
$PN"H7"65;
"MKB_CHECK3"
$PN"CB7"83;
"MKB_DATA3"
$PN"CD7"120;
"MKB_DATA12"
$PN"CM6"121;
"MKB_DATA23"
$PN"CY7"95;
"MKA1_RSP_L"
$PN"BP7"0;
"MKA_DATA3"
$PN"G7"150;
"MKA_DATA17"
$PN"V7"129;
"MKA_DATA28"
$PN"AG5"130;
"MKA_DQS_H0"
$PN"G5"78;
"MKA_DQS_L4"
$PN"AM6"66;
"MKB_CHECK2"
$PN"CA5"84;
"MKB_DATA2"
$PN"CC5"122;
"MKB_DATA11"
$PN"CK7"123;
"MKB_DATA22"
$PN"CW5"96;
"MK_ALERT_L"
$PN"AT7"13;
"MKA0_RSP_L"
$PN"BN7"18;
"MKA_CHECK7"
$PN"AR7"85;
"MKA_DATA2"
$PN"F6"151;
"MKA_DATA16"
$PN"U5"131;
"MKA_DATA27"
$PN"AE7"132;
"MKA_DQS_L3"
$PN"AF6"67;
"MKB_CHECK1"
$PN"CA7"86;
"MKB_DATA1"
$PN"CC7"124;
"MKB_DATA10"
$PN"CJ5"125;
"MKB_DATA21"
$PN"CW7"97;
"MKA_CHECK6"
$PN"AP6"87;
"MKA_DATA1"
$PN"F7"152;
"MKA_DATA15"
$PN"U7"133;
"MKA_DATA26"
$PN"AD6"134;
"MKA_DQS_L2"
$PN"Y6"68;
"MKB1_CS_L1"
$PN"BM6"0;
"MKB_CHECK0"
$PN"BY6"88;
"MKB_DATA0"
$PN"CB6"135;
"MKB_DATA20"
$PN"CV6"98;
"MKB_DATA31"
$PN"DF7"99;
"MKB_DQS_H9"
$PN"BV6"41;
"MK1_CLK_L"
$PN"BG5"0;
"MKA_CHECK5"
$PN"AP7"100;
"MKA_DATA0"
$PN"E5"153;
"MKA_DATA14"
$PN"T6"154;
"MKA_DATA25"
$PN"AD7"136;
"MKA_DQS_L1"
$PN"P6"69;
"MKB0_CS_L1"
$PN"BN5"21;
"MKB1_CS_L0"
$PN"BL5"0;
"MKB_CA6"
$PN"BK6"25;
"MKB_DATA30"
$PN"DE5"101;
"MKB_DQS_H8"
$PN"DD7"42;
"MK0_CLK_L"
$PN"BD6"14;
"MKA_CA6"
$PN"BB7"27;
"MKA_CHECK4"
$PN"AN5"102;
"MKA_DATA13"
$PN"T7"155;
"MKA_DATA24"
$PN"AC5"137;
"MKA_DQS_L0"
$PN"H6"70;
"MKB0_CS_L0"
$PN"BM7"20;
"MKB_CA5"
$PN"BK7"28;
"MKB_DQS_H7"
$PN"CV7"53;
"MKA_CA5"
$PN"BB6"29;
"MKA_CHECK3"
$PN"AL7"103;
"MKA_DATA12"
$PN"R5"156;
"MKA_DATA23"
$PN"AC7"138;
"MKB_CA4"
$PN"BJ7"30;
"MKB_DQS_H6"
$PN"CM7"54;
"MK_RESET_L"
$PN"AU7"24;
"MKA_CA4"
$PN"BA5"31;
"MKA_CHECK2"
$PN"AK6"104;
"MKA_DATA11"
$PN"N7"157;
"MKA_DATA22"
$PN"AB6"139;
"MKB_CA3"
$PN"BJ5"32;
"MKB_DQS_H5"
$PN"CF7"55;
"MKB_DQS_L9"
$PN"BW5"33;
"MK1_CLK_H"
$PN"BF6"0;
"MKA_CA3"
$PN"BA7"34;
"MKA_CHECK1"
$PN"AK7"105;
"MKA_DATA10"
$PN"M6"158;
"MKA_DATA21"
$PN"AB7"140;
"MKB_CA2"
$PN"BH6"35;
"MKB_DQS_H4"
$PN"BY7"56;
"MKB_DQS_L8"
$PN"DC7"36;
"MK0_CLK_H"
$PN"BC5"15;
"MKA1_CS_L1"
$PN"AW7"0;
"MKA_CA2"
$PN"AY7"37;
"MKA_CHECK0"
$PN"AJ5"106;
"MKA_DATA20"
$PN"AA5"141;
"MKA_DATA31"
$PN"AJ7"142;
"MKA_DQS_H9"
$PN"AN7"60;
"MKB_CA1"
$PN"BH7"38;
"MKB_DQS_H3"
$PN"DB6"57;
"MKB_DQS_L7"
$PN"CU7"51;
"MKA0_CS_L1"
$PN"AV7"17;
"MKA1_CS_L0"
$PN"AV6"0;
"MKA_CA1"
$PN"AY6"39;
"MKA_DATA30"
$PN"AH6"143;
"MKA_DQS_H8"
$PN"AG7"61;
"MKB_CA0"
$PN"BG7"40;
"MKB_DATA19"
$PN"CT7"107;
"MKB_DQS_H2"
$PN"CT6"62;
"MKB_DQS_L6"
$PN"CL7"52;
%"TAP"
"1","(-3225,5900)","0","mstr_standard","I161";
;
CDS_LIB"mstr_standard"
BODY_TYPE"PLUMBING"
HDL_TAP"TRUE";
"B \NAC \NWC"1;
"S \NAC"
BN"0"153;
%"TAP"
"1","(-3225,5850)","0","mstr_standard","I162";
;
CDS_LIB"mstr_standard"
BODY_TYPE"PLUMBING"
HDL_TAP"TRUE";
"B \NAC \NWC"1;
"S \NAC"
BN"1"152;
%"TAP"
"1","(-3225,5800)","0","mstr_standard","I163";
;
CDS_LIB"mstr_standard"
BODY_TYPE"PLUMBING"
HDL_TAP"TRUE";
"B \NAC \NWC"1;
"S \NAC"
BN"2"151;
%"TAP"
"1","(-3225,5750)","0","mstr_standard","I164";
;
CDS_LIB"mstr_standard"
BODY_TYPE"PLUMBING"
HDL_TAP"TRUE";
"B \NAC \NWC"1;
"S \NAC"
BN"3"150;
%"TAP"
"1","(-3225,5650)","0","mstr_standard","I165";
;
CDS_LIB"mstr_standard"
BODY_TYPE"PLUMBING"
HDL_TAP"TRUE";
"B \NAC \NWC"1;
"S \NAC"
BN"5"148;
%"TAP"
"1","(-3225,5700)","0","mstr_standard","I166";
;
CDS_LIB"mstr_standard"
BODY_TYPE"PLUMBING"
HDL_TAP"TRUE";
"B \NAC \NWC"1;
"S \NAC"
BN"4"149;
%"TAP"
"1","(-3225,5600)","0","mstr_standard","I167";
;
CDS_LIB"mstr_standard"
BODY_TYPE"PLUMBING"
HDL_TAP"TRUE";
"B \NAC \NWC"1;
"S \NAC"
BN"6"147;
%"TAP"
"1","(-3225,5550)","0","mstr_standard","I168";
;
CDS_LIB"mstr_standard"
BODY_TYPE"PLUMBING"
HDL_TAP"TRUE";
"B \NAC \NWC"1;
"S \NAC"
BN"7"146;
%"TAP"
"1","(-3225,5400)","0","mstr_standard","I169";
;
CDS_LIB"mstr_standard"
BODY_TYPE"PLUMBING"
HDL_TAP"TRUE";
"B \NAC \NWC"1;
"S \NAC"
BN"9"144;
%"TAP"
"1","(-3225,5450)","0","mstr_standard","I170";
;
CDS_LIB"mstr_standard"
BODY_TYPE"PLUMBING"
HDL_TAP"TRUE";
"B \NAC \NWC"1;
"S \NAC"
BN"8"145;
%"TAP"
"1","(-3225,5350)","0","mstr_standard","I171";
;
CDS_LIB"mstr_standard"
BODY_TYPE"PLUMBING"
HDL_TAP"TRUE";
"B \NAC \NWC"1;
"S \NAC"
BN"10"158;
%"TAP"
"1","(-3225,5300)","0","mstr_standard","I172";
;
CDS_LIB"mstr_standard"
BODY_TYPE"PLUMBING"
HDL_TAP"TRUE";
"B \NAC \NWC"1;
"S \NAC"
BN"11"157;
%"TAP"
"1","(-3225,5250)","0","mstr_standard","I173";
;
CDS_LIB"mstr_standard"
BODY_TYPE"PLUMBING"
HDL_TAP"TRUE";
"B \NAC \NWC"1;
"S \NAC"
BN"12"156;
%"TAP"
"1","(-3225,5200)","0","mstr_standard","I174";
;
CDS_LIB"mstr_standard"
BODY_TYPE"PLUMBING"
HDL_TAP"TRUE";
"B \NAC \NWC"1;
"S \NAC"
BN"13"155;
%"TAP"
"1","(-3225,5150)","0","mstr_standard","I175";
;
CDS_LIB"mstr_standard"
BODY_TYPE"PLUMBING"
HDL_TAP"TRUE";
"B \NAC \NWC"1;
"S \NAC"
BN"14"154;
%"TAP"
"1","(-3225,4950)","0","mstr_standard","I176";
;
CDS_LIB"mstr_standard"
BODY_TYPE"PLUMBING"
HDL_TAP"TRUE";
"B \NAC \NWC"1;
"S \NAC"
BN"17"129;
%"TAP"
"1","(-3225,5100)","0","mstr_standard","I177";
;
CDS_LIB"mstr_standard"
BODY_TYPE"PLUMBING"
HDL_TAP"TRUE";
"B \NAC \NWC"1;
"S \NAC"
BN"15"133;
%"TAP"
"1","(-3225,5000)","0","mstr_standard","I178";
;
CDS_LIB"mstr_standard"
BODY_TYPE"PLUMBING"
HDL_TAP"TRUE";
"B \NAC \NWC"1;
"S \NAC"
BN"16"131;
%"TAP"
"1","(-3225,4900)","0","mstr_standard","I179";
;
CDS_LIB"mstr_standard"
BODY_TYPE"PLUMBING"
HDL_TAP"TRUE";
"B \NAC \NWC"1;
"S \NAC"
BN"18"127;
%"TAP"
"1","(-3225,4850)","0","mstr_standard","I180";
;
CDS_LIB"mstr_standard"
BODY_TYPE"PLUMBING"
HDL_TAP"TRUE";
"B \NAC \NWC"1;
"S \NAC"
BN"19"126;
%"TAP"
"1","(-3225,4800)","0","mstr_standard","I181";
;
CDS_LIB"mstr_standard"
BODY_TYPE"PLUMBING"
HDL_TAP"TRUE";
"B \NAC \NWC"1;
"S \NAC"
BN"20"141;
%"TAP"
"1","(-3225,4750)","0","mstr_standard","I182";
;
CDS_LIB"mstr_standard"
BODY_TYPE"PLUMBING"
HDL_TAP"TRUE";
"B \NAC \NWC"1;
"S \NAC"
BN"21"140;
%"TAP"
"1","(-3225,4700)","0","mstr_standard","I183";
;
CDS_LIB"mstr_standard"
BODY_TYPE"PLUMBING"
HDL_TAP"TRUE";
"B \NAC \NWC"1;
"S \NAC"
BN"22"139;
%"TAP"
"1","(-3225,4650)","0","mstr_standard","I184";
;
CDS_LIB"mstr_standard"
BODY_TYPE"PLUMBING"
HDL_TAP"TRUE";
"B \NAC \NWC"1;
"S \NAC"
BN"23"138;
%"TAP"
"1","(-3225,4550)","0","mstr_standard","I185";
;
CDS_LIB"mstr_standard"
BODY_TYPE"PLUMBING"
HDL_TAP"TRUE";
"B \NAC \NWC"1;
"S \NAC"
BN"24"137;
%"TAP"
"1","(-3225,4500)","0","mstr_standard","I186";
;
CDS_LIB"mstr_standard"
BODY_TYPE"PLUMBING"
HDL_TAP"TRUE";
"B \NAC \NWC"1;
"S \NAC"
BN"25"136;
%"TAP"
"1","(-3225,4450)","0","mstr_standard","I187";
;
CDS_LIB"mstr_standard"
BODY_TYPE"PLUMBING"
HDL_TAP"TRUE";
"B \NAC \NWC"1;
"S \NAC"
BN"26"134;
%"TAP"
"1","(-3225,4400)","0","mstr_standard","I188";
;
CDS_LIB"mstr_standard"
BODY_TYPE"PLUMBING"
HDL_TAP"TRUE";
"B \NAC \NWC"1;
"S \NAC"
BN"27"132;
%"TAP"
"1","(-3225,4350)","0","mstr_standard","I189";
;
CDS_LIB"mstr_standard"
BODY_TYPE"PLUMBING"
HDL_TAP"TRUE";
"B \NAC \NWC"1;
"S \NAC"
BN"28"130;
%"TAP"
"1","(-3225,4300)","0","mstr_standard","I190";
;
CDS_LIB"mstr_standard"
BODY_TYPE"PLUMBING"
HDL_TAP"TRUE";
"B \NAC \NWC"1;
"S \NAC"
BN"29"128;
%"TAP"
"1","(-3225,4250)","0","mstr_standard","I191";
;
CDS_LIB"mstr_standard"
BODY_TYPE"PLUMBING"
HDL_TAP"TRUE";
"B \NAC \NWC"1;
"S \NAC"
BN"30"143;
%"TAP"
"1","(-3225,4200)","0","mstr_standard","I192";
;
CDS_LIB"mstr_standard"
BODY_TYPE"PLUMBING"
HDL_TAP"TRUE";
"B \NAC \NWC"1;
"S \NAC"
BN"31"142;
%"TAP"
"1","(-3225,4100)","0","mstr_standard","I193";
;
CDS_LIB"mstr_standard"
BODY_TYPE"PLUMBING"
HDL_TAP"TRUE";
"B \NAC \NWC"2;
"S \NAC"
BN"0"135;
%"TAP"
"1","(-3225,4050)","0","mstr_standard","I196";
;
CDS_LIB"mstr_standard"
BODY_TYPE"PLUMBING"
HDL_TAP"TRUE";
"B \NAC \NWC"2;
"S \NAC"
BN"1"124;
%"TAP"
"1","(-3225,4000)","0","mstr_standard","I197";
;
CDS_LIB"mstr_standard"
BODY_TYPE"PLUMBING"
HDL_TAP"TRUE";
"B \NAC \NWC"2;
"S \NAC"
BN"2"122;
%"TAP"
"1","(-3225,3950)","0","mstr_standard","I198";
;
CDS_LIB"mstr_standard"
BODY_TYPE"PLUMBING"
HDL_TAP"TRUE";
"B \NAC \NWC"2;
"S \NAC"
BN"3"120;
%"TAP"
"1","(-3225,3850)","0","mstr_standard","I199";
;
CDS_LIB"mstr_standard"
BODY_TYPE"PLUMBING"
HDL_TAP"TRUE";
"B \NAC \NWC"2;
"S \NAC"
BN"5"116;
%"TAP"
"1","(-3225,3900)","0","mstr_standard","I200";
;
CDS_LIB"mstr_standard"
BODY_TYPE"PLUMBING"
HDL_TAP"TRUE";
"B \NAC \NWC"2;
"S \NAC"
BN"4"118;
%"TAP"
"1","(-3225,3800)","0","mstr_standard","I201";
;
CDS_LIB"mstr_standard"
BODY_TYPE"PLUMBING"
HDL_TAP"TRUE";
"B \NAC \NWC"2;
"S \NAC"
BN"6"114;
%"TAP"
"1","(-3225,3750)","0","mstr_standard","I202";
;
CDS_LIB"mstr_standard"
BODY_TYPE"PLUMBING"
HDL_TAP"TRUE";
"B \NAC \NWC"2;
"S \NAC"
BN"7"112;
%"TAP"
"1","(-3225,3600)","0","mstr_standard","I203";
;
CDS_LIB"mstr_standard"
BODY_TYPE"PLUMBING"
HDL_TAP"TRUE";
"B \NAC \NWC"2;
"S \NAC"
BN"9"108;
%"TAP"
"1","(-3225,3650)","0","mstr_standard","I204";
;
CDS_LIB"mstr_standard"
BODY_TYPE"PLUMBING"
HDL_TAP"TRUE";
"B \NAC \NWC"2;
"S \NAC"
BN"8"110;
%"TAP"
"1","(-3225,3550)","0","mstr_standard","I205";
;
CDS_LIB"mstr_standard"
BODY_TYPE"PLUMBING"
HDL_TAP"TRUE";
"B \NAC \NWC"2;
"S \NAC"
BN"10"125;
%"TAP"
"1","(-3225,3500)","0","mstr_standard","I206";
;
CDS_LIB"mstr_standard"
BODY_TYPE"PLUMBING"
HDL_TAP"TRUE";
"B \NAC \NWC"2;
"S \NAC"
BN"11"123;
%"TAP"
"1","(-3225,3450)","0","mstr_standard","I207";
;
CDS_LIB"mstr_standard"
BODY_TYPE"PLUMBING"
HDL_TAP"TRUE";
"B \NAC \NWC"2;
"S \NAC"
BN"12"121;
%"TAP"
"1","(-3225,3350)","0","mstr_standard","I208";
;
CDS_LIB"mstr_standard"
BODY_TYPE"PLUMBING"
HDL_TAP"TRUE";
"B \NAC \NWC"2;
"S \NAC"
BN"14"117;
%"TAP"
"1","(-3225,3400)","0","mstr_standard","I209";
;
CDS_LIB"mstr_standard"
BODY_TYPE"PLUMBING"
HDL_TAP"TRUE";
"B \NAC \NWC"2;
"S \NAC"
BN"13"119;
%"TAP"
"1","(-3225,3300)","0","mstr_standard","I210";
;
CDS_LIB"mstr_standard"
BODY_TYPE"PLUMBING"
HDL_TAP"TRUE";
"B \NAC \NWC"2;
"S \NAC"
BN"15"115;
%"TAP"
"1","(-3225,3200)","0","mstr_standard","I211";
;
CDS_LIB"mstr_standard"
BODY_TYPE"PLUMBING"
HDL_TAP"TRUE";
"B \NAC \NWC"2;
"S \NAC"
BN"16"113;
%"TAP"
"1","(-3225,3150)","0","mstr_standard","I212";
;
CDS_LIB"mstr_standard"
BODY_TYPE"PLUMBING"
HDL_TAP"TRUE";
"B \NAC \NWC"2;
"S \NAC"
BN"17"111;
%"TAP"
"1","(-3225,3100)","0","mstr_standard","I213";
;
CDS_LIB"mstr_standard"
BODY_TYPE"PLUMBING"
HDL_TAP"TRUE";
"B \NAC \NWC"2;
"S \NAC"
BN"18"109;
%"TAP"
"1","(-3225,3050)","0","mstr_standard","I214";
;
CDS_LIB"mstr_standard"
BODY_TYPE"PLUMBING"
HDL_TAP"TRUE";
"B \NAC \NWC"2;
"S \NAC"
BN"19"107;
%"TAP"
"1","(-3225,2950)","0","mstr_standard","I215";
;
CDS_LIB"mstr_standard"
BODY_TYPE"PLUMBING"
HDL_TAP"TRUE";
"B \NAC \NWC"2;
"S \NAC"
BN"21"97;
%"TAP"
"1","(-3225,3000)","0","mstr_standard","I216";
;
CDS_LIB"mstr_standard"
BODY_TYPE"PLUMBING"
HDL_TAP"TRUE";
"B \NAC \NWC"2;
"S \NAC"
BN"20"98;
%"TAP"
"1","(-3225,2900)","0","mstr_standard","I217";
;
CDS_LIB"mstr_standard"
BODY_TYPE"PLUMBING"
HDL_TAP"TRUE";
"B \NAC \NWC"2;
"S \NAC"
BN"22"96;
%"TAP"
"1","(-3225,2850)","0","mstr_standard","I218";
;
CDS_LIB"mstr_standard"
BODY_TYPE"PLUMBING"
HDL_TAP"TRUE";
"B \NAC \NWC"2;
"S \NAC"
BN"23"95;
%"TAP"
"1","(-3225,2750)","0","mstr_standard","I219";
;
CDS_LIB"mstr_standard"
BODY_TYPE"PLUMBING"
HDL_TAP"TRUE";
"B \NAC \NWC"2;
"S \NAC"
BN"24"94;
%"TAP"
"1","(-3225,2700)","0","mstr_standard","I220";
;
CDS_LIB"mstr_standard"
BODY_TYPE"PLUMBING"
HDL_TAP"TRUE";
"B \NAC \NWC"2;
"S \NAC"
BN"25"93;
%"TAP"
"1","(-3225,2650)","0","mstr_standard","I221";
;
CDS_LIB"mstr_standard"
BODY_TYPE"PLUMBING"
HDL_TAP"TRUE";
"B \NAC \NWC"2;
"S \NAC"
BN"26"92;
%"TAP"
"1","(-3225,2600)","0","mstr_standard","I222";
;
CDS_LIB"mstr_standard"
BODY_TYPE"PLUMBING"
HDL_TAP"TRUE";
"B \NAC \NWC"2;
"S \NAC"
BN"27"91;
%"TAP"
"1","(-3225,2500)","0","mstr_standard","I223";
;
CDS_LIB"mstr_standard"
BODY_TYPE"PLUMBING"
HDL_TAP"TRUE";
"B \NAC \NWC"2;
"S \NAC"
BN"29"89;
%"TAP"
"1","(-3225,2550)","0","mstr_standard","I224";
;
CDS_LIB"mstr_standard"
BODY_TYPE"PLUMBING"
HDL_TAP"TRUE";
"B \NAC \NWC"2;
"S \NAC"
BN"28"90;
%"TAP"
"1","(-3225,2450)","0","mstr_standard","I225";
;
CDS_LIB"mstr_standard"
BODY_TYPE"PLUMBING"
HDL_TAP"TRUE";
"B \NAC \NWC"2;
"S \NAC"
BN"30"101;
%"TAP"
"1","(-3225,2400)","0","mstr_standard","I226";
;
CDS_LIB"mstr_standard"
BODY_TYPE"PLUMBING"
HDL_TAP"TRUE";
"B \NAC \NWC"2;
"S \NAC"
BN"31"99;
%"TAP"
"1","(-3225,2300)","0","mstr_standard","I227";
;
CDS_LIB"mstr_standard"
BODY_TYPE"PLUMBING"
HDL_TAP"TRUE";
"B \NAC \NWC"3;
"S \NAC"
BN"0"106;
%"TAP"
"1","(-3225,2250)","0","mstr_standard","I228";
;
CDS_LIB"mstr_standard"
BODY_TYPE"PLUMBING"
HDL_TAP"TRUE";
"B \NAC \NWC"3;
"S \NAC"
BN"1"105;
%"TAP"
"1","(-3225,2200)","0","mstr_standard","I229";
;
CDS_LIB"mstr_standard"
BODY_TYPE"PLUMBING"
HDL_TAP"TRUE";
"B \NAC \NWC"3;
"S \NAC"
BN"2"104;
%"TAP"
"1","(-3225,2150)","0","mstr_standard","I230";
;
CDS_LIB"mstr_standard"
BODY_TYPE"PLUMBING"
HDL_TAP"TRUE";
"B \NAC \NWC"3;
"S \NAC"
BN"3"103;
%"TAP"
"1","(-3225,2100)","0","mstr_standard","I231";
;
CDS_LIB"mstr_standard"
BODY_TYPE"PLUMBING"
HDL_TAP"TRUE";
"B \NAC \NWC"3;
"S \NAC"
BN"4"102;
%"TAP"
"1","(-3225,2050)","0","mstr_standard","I232";
;
CDS_LIB"mstr_standard"
BODY_TYPE"PLUMBING"
HDL_TAP"TRUE";
"B \NAC \NWC"3;
"S \NAC"
BN"5"100;
%"TAP"
"1","(-3225,2000)","0","mstr_standard","I234";
;
CDS_LIB"mstr_standard"
BODY_TYPE"PLUMBING"
HDL_TAP"TRUE";
"B \NAC \NWC"3;
"S \NAC"
BN"6"87;
%"TAP"
"1","(-3225,1950)","0","mstr_standard","I235";
;
CDS_LIB"mstr_standard"
BODY_TYPE"PLUMBING"
HDL_TAP"TRUE";
"B \NAC \NWC"3;
"S \NAC"
BN"7"85;
%"TAP"
"1","(-3225,1800)","0","mstr_standard","I236";
;
CDS_LIB"mstr_standard"
BODY_TYPE"PLUMBING"
HDL_TAP"TRUE";
"B \NAC \NWC"4;
"S \NAC"
BN"1"86;
%"TAP"
"1","(-3225,1850)","0","mstr_standard","I237";
;
CDS_LIB"mstr_standard"
BODY_TYPE"PLUMBING"
HDL_TAP"TRUE";
"B \NAC \NWC"4;
"S \NAC"
BN"0"88;
%"TAP"
"1","(-3225,1750)","0","mstr_standard","I238";
;
CDS_LIB"mstr_standard"
BODY_TYPE"PLUMBING"
HDL_TAP"TRUE";
"B \NAC \NWC"4;
"S \NAC"
BN"2"84;
%"TAP"
"1","(-3225,1700)","0","mstr_standard","I239";
;
CDS_LIB"mstr_standard"
BODY_TYPE"PLUMBING"
HDL_TAP"TRUE";
"B \NAC \NWC"4;
"S \NAC"
BN"3"83;
%"TAP"
"1","(-3225,1600)","0","mstr_standard","I240";
;
CDS_LIB"mstr_standard"
BODY_TYPE"PLUMBING"
HDL_TAP"TRUE";
"B \NAC \NWC"4;
"S \NAC"
BN"5"81;
%"TAP"
"1","(-3225,1650)","0","mstr_standard","I241";
;
CDS_LIB"mstr_standard"
BODY_TYPE"PLUMBING"
HDL_TAP"TRUE";
"B \NAC \NWC"4;
"S \NAC"
BN"4"82;
%"TAP"
"1","(-3225,1550)","0","mstr_standard","I242";
;
CDS_LIB"mstr_standard"
BODY_TYPE"PLUMBING"
HDL_TAP"TRUE";
"B \NAC \NWC"4;
"S \NAC"
BN"6"80;
%"TAP"
"1","(-3225,1500)","0","mstr_standard","I243";
;
CDS_LIB"mstr_standard"
BODY_TYPE"PLUMBING"
HDL_TAP"TRUE";
"B \NAC \NWC"4;
"S \NAC"
BN"7"79;
%"TAP"
"1","(-5650,5900)","2","mstr_standard","I244";
;
CDS_LIB"mstr_standard"
BODY_TYPE"PLUMBING"
HDL_TAP"TRUE";
"B \NAC \NWC"5;
"S \NAC"
BN"0"78;
%"TAP"
"1","(-5650,5800)","2","mstr_standard","I245";
;
CDS_LIB"mstr_standard"
BODY_TYPE"PLUMBING"
HDL_TAP"TRUE";
"B \NAC \NWC"5;
"S \NAC"
BN"1"77;
%"TAP"
"1","(-5650,5700)","2","mstr_standard","I246";
;
CDS_LIB"mstr_standard"
BODY_TYPE"PLUMBING"
HDL_TAP"TRUE";
"B \NAC \NWC"5;
"S \NAC"
BN"2"76;
%"TAP"
"1","(-5650,5600)","2","mstr_standard","I247";
;
CDS_LIB"mstr_standard"
BODY_TYPE"PLUMBING"
HDL_TAP"TRUE";
"B \NAC \NWC"5;
"S \NAC"
BN"3"75;
%"TAP"
"1","(-5650,5400)","2","mstr_standard","I248";
;
CDS_LIB"mstr_standard"
BODY_TYPE"PLUMBING"
HDL_TAP"TRUE";
"B \NAC \NWC"5;
"S \NAC"
BN"5"73;
%"TAP"
"1","(-5650,5500)","2","mstr_standard","I249";
;
CDS_LIB"mstr_standard"
BODY_TYPE"PLUMBING"
HDL_TAP"TRUE";
"B \NAC \NWC"5;
"S \NAC"
BN"4"74;
%"TAP"
"1","(-5650,5300)","2","mstr_standard","I250";
;
CDS_LIB"mstr_standard"
BODY_TYPE"PLUMBING"
HDL_TAP"TRUE";
"B \NAC \NWC"5;
"S \NAC"
BN"6"72;
%"TAP"
"1","(-5650,5200)","2","mstr_standard","I251";
;
CDS_LIB"mstr_standard"
BODY_TYPE"PLUMBING"
HDL_TAP"TRUE";
"B \NAC \NWC"5;
"S \NAC"
BN"7"71;
%"TAP"
"1","(-5850,5750)","2","mstr_standard","I252";
;
CDS_LIB"mstr_standard"
BODY_TYPE"PLUMBING"
HDL_TAP"TRUE";
"B \NAC \NWC"9;
"S \NAC"
BN"1"69;
%"TAP"
"1","(-5850,5850)","2","mstr_standard","I253";
;
CDS_LIB"mstr_standard"
BODY_TYPE"PLUMBING"
HDL_TAP"TRUE";
"B \NAC \NWC"9;
"S \NAC"
BN"0"70;
%"TAP"
"1","(-5850,5650)","2","mstr_standard","I254";
;
CDS_LIB"mstr_standard"
BODY_TYPE"PLUMBING"
HDL_TAP"TRUE";
"B \NAC \NWC"9;
"S \NAC"
BN"2"68;
%"TAP"
"1","(-5850,5550)","2","mstr_standard","I255";
;
CDS_LIB"mstr_standard"
BODY_TYPE"PLUMBING"
HDL_TAP"TRUE";
"B \NAC \NWC"9;
"S \NAC"
BN"3"67;
%"TAP"
"1","(-5850,5450)","2","mstr_standard","I256";
;
CDS_LIB"mstr_standard"
BODY_TYPE"PLUMBING"
HDL_TAP"TRUE";
"B \NAC \NWC"9;
"S \NAC"
BN"4"66;
%"TAP"
"1","(-5850,5350)","2","mstr_standard","I257";
;
CDS_LIB"mstr_standard"
BODY_TYPE"PLUMBING"
HDL_TAP"TRUE";
"B \NAC \NWC"9;
"S \NAC"
BN"5"65;
%"TAP"
"1","(-5850,5250)","2","mstr_standard","I258";
;
CDS_LIB"mstr_standard"
BODY_TYPE"PLUMBING"
HDL_TAP"TRUE";
"B \NAC \NWC"9;
"S \NAC"
BN"6"64;
%"TAP"
"1","(-5850,5150)","2","mstr_standard","I259";
;
CDS_LIB"mstr_standard"
BODY_TYPE"PLUMBING"
HDL_TAP"TRUE";
"B \NAC \NWC"9;
"S \NAC"
BN"7"63;
%"TAP"
"1","(-5650,5100)","2","mstr_standard","I260";
;
CDS_LIB"mstr_standard"
BODY_TYPE"PLUMBING"
HDL_TAP"TRUE";
"B \NAC \NWC"5;
"S \NAC"
BN"8"61;
%"TAP"
"1","(-5650,5000)","2","mstr_standard","I261";
;
CDS_LIB"mstr_standard"
BODY_TYPE"PLUMBING"
HDL_TAP"TRUE";
"B \NAC \NWC"5;
"S \NAC"
BN"9"60;
%"TAP"
"1","(-5650,4850)","2","mstr_standard","I262";
;
CDS_LIB"mstr_standard"
BODY_TYPE"PLUMBING"
HDL_TAP"TRUE";
"B \NAC \NWC"6;
"S \NAC"
BN"0"59;
%"TAP"
"1","(-5650,4750)","2","mstr_standard","I263";
;
CDS_LIB"mstr_standard"
BODY_TYPE"PLUMBING"
HDL_TAP"TRUE";
"B \NAC \NWC"6;
"S \NAC"
BN"1"58;
%"TAP"
"1","(-5650,4650)","2","mstr_standard","I264";
;
CDS_LIB"mstr_standard"
BODY_TYPE"PLUMBING"
HDL_TAP"TRUE";
"B \NAC \NWC"6;
"S \NAC"
BN"2"62;
%"TAP"
"1","(-5650,4550)","2","mstr_standard","I265";
;
CDS_LIB"mstr_standard"
BODY_TYPE"PLUMBING"
HDL_TAP"TRUE";
"B \NAC \NWC"6;
"S \NAC"
BN"3"57;
%"TAP"
"1","(-5650,4450)","2","mstr_standard","I266";
;
CDS_LIB"mstr_standard"
BODY_TYPE"PLUMBING"
HDL_TAP"TRUE";
"B \NAC \NWC"6;
"S \NAC"
BN"4"56;
%"TAP"
"1","(-5650,4250)","2","mstr_standard","I267";
;
CDS_LIB"mstr_standard"
BODY_TYPE"PLUMBING"
HDL_TAP"TRUE";
"B \NAC \NWC"6;
"S \NAC"
BN"6"54;
%"TAP"
"1","(-5650,4350)","2","mstr_standard","I268";
;
CDS_LIB"mstr_standard"
BODY_TYPE"PLUMBING"
HDL_TAP"TRUE";
"B \NAC \NWC"6;
"S \NAC"
BN"5"55;
%"TAP"
"1","(-5650,4150)","2","mstr_standard","I269";
;
CDS_LIB"mstr_standard"
BODY_TYPE"PLUMBING"
HDL_TAP"TRUE";
"B \NAC \NWC"6;
"S \NAC"
BN"7"53;
%"TAP"
"1","(-5850,4950)","2","mstr_standard","I270";
;
CDS_LIB"mstr_standard"
BODY_TYPE"PLUMBING"
HDL_TAP"TRUE";
"B \NAC \NWC"9;
"S \NAC"
BN"9"45;
%"TAP"
"1","(-5850,5050)","2","mstr_standard","I271";
;
CDS_LIB"mstr_standard"
BODY_TYPE"PLUMBING"
HDL_TAP"TRUE";
"B \NAC \NWC"9;
"S \NAC"
BN"8"47;
%"TAP"
"1","(-5850,4800)","2","mstr_standard","I272";
;
CDS_LIB"mstr_standard"
BODY_TYPE"PLUMBING"
HDL_TAP"TRUE";
"B \NAC \NWC"10;
"S \NAC"
BN"0"50;
%"TAP"
"1","(-5850,4700)","2","mstr_standard","I273";
;
CDS_LIB"mstr_standard"
BODY_TYPE"PLUMBING"
HDL_TAP"TRUE";
"B \NAC \NWC"10;
"S \NAC"
BN"1"49;
%"TAP"
"1","(-5850,4600)","2","mstr_standard","I274";
;
CDS_LIB"mstr_standard"
BODY_TYPE"PLUMBING"
HDL_TAP"TRUE";
"B \NAC \NWC"10;
"S \NAC"
BN"2"48;
%"TAP"
"1","(-5850,4500)","2","mstr_standard","I275";
;
CDS_LIB"mstr_standard"
BODY_TYPE"PLUMBING"
HDL_TAP"TRUE";
"B \NAC \NWC"10;
"S \NAC"
BN"3"46;
%"TAP"
"1","(-5850,4400)","2","mstr_standard","I276";
;
CDS_LIB"mstr_standard"
BODY_TYPE"PLUMBING"
HDL_TAP"TRUE";
"B \NAC \NWC"10;
"S \NAC"
BN"4"44;
%"TAP"
"1","(-5850,4200)","2","mstr_standard","I277";
;
CDS_LIB"mstr_standard"
BODY_TYPE"PLUMBING"
HDL_TAP"TRUE";
"B \NAC \NWC"10;
"S \NAC"
BN"6"52;
%"TAP"
"1","(-5850,4300)","2","mstr_standard","I278";
;
CDS_LIB"mstr_standard"
BODY_TYPE"PLUMBING"
HDL_TAP"TRUE";
"B \NAC \NWC"10;
"S \NAC"
BN"5"43;
%"TAP"
"1","(-5850,4100)","2","mstr_standard","I279";
;
CDS_LIB"mstr_standard"
BODY_TYPE"PLUMBING"
HDL_TAP"TRUE";
"B \NAC \NWC"10;
"S \NAC"
BN"7"51;
%"TAP"
"1","(-5650,3950)","2","mstr_standard","I284";
;
CDS_LIB"mstr_standard"
BODY_TYPE"PLUMBING"
HDL_TAP"TRUE";
"B \NAC \NWC"6;
"S \NAC"
BN"9"41;
%"TAP"
"1","(-5650,4050)","2","mstr_standard","I285";
;
CDS_LIB"mstr_standard"
BODY_TYPE"PLUMBING"
HDL_TAP"TRUE";
"B \NAC \NWC"6;
"S \NAC"
BN"8"42;
%"TAP"
"1","(-5850,4000)","2","mstr_standard","I286";
;
CDS_LIB"mstr_standard"
BODY_TYPE"PLUMBING"
HDL_TAP"TRUE";
"B \NAC \NWC"10;
"S \NAC"
BN"8"36;
%"TAP"
"1","(-5850,3900)","2","mstr_standard","I287";
;
CDS_LIB"mstr_standard"
BODY_TYPE"PLUMBING"
HDL_TAP"TRUE";
"B \NAC \NWC"10;
"S \NAC"
BN"9"33;
%"TAP"
"1","(-5850,3600)","2","mstr_standard","I288";
;
CDS_LIB"mstr_standard"
BODY_TYPE"PLUMBING"
HDL_TAP"TRUE";
"B \NAC \NWC"7;
"S \NAC"
BN"3"34;
%"TAP"
"1","(-5850,3750)","2","mstr_standard","I289";
;
CDS_LIB"mstr_standard"
BODY_TYPE"PLUMBING"
HDL_TAP"TRUE";
"B \NAC \NWC"7;
"S \NAC"
BN"0"26;
%"TAP"
"1","(-5850,3700)","2","mstr_standard","I290";
;
CDS_LIB"mstr_standard"
BODY_TYPE"PLUMBING"
HDL_TAP"TRUE";
"B \NAC \NWC"7;
"S \NAC"
BN"1"39;
%"TAP"
"1","(-5850,3650)","2","mstr_standard","I291";
;
CDS_LIB"mstr_standard"
BODY_TYPE"PLUMBING"
HDL_TAP"TRUE";
"B \NAC \NWC"7;
"S \NAC"
BN"2"37;
%"TAP"
"1","(-5850,3350)","2","mstr_standard","I292";
;
CDS_LIB"mstr_standard"
BODY_TYPE"PLUMBING"
HDL_TAP"TRUE";
"B \NAC \NWC"8;
"S \NAC"
BN"0"40;
%"TAP"
"1","(-5850,3550)","2","mstr_standard","I293";
;
CDS_LIB"mstr_standard"
BODY_TYPE"PLUMBING"
HDL_TAP"TRUE";
"B \NAC \NWC"7;
"S \NAC"
BN"4"31;
%"TAP"
"1","(-5850,3450)","2","mstr_standard","I294";
;
CDS_LIB"mstr_standard"
BODY_TYPE"PLUMBING"
HDL_TAP"TRUE";
"B \NAC \NWC"7;
"S \NAC"
BN"6"27;
%"TAP"
"1","(-5850,3500)","2","mstr_standard","I295";
;
CDS_LIB"mstr_standard"
BODY_TYPE"PLUMBING"
HDL_TAP"TRUE";
"B \NAC \NWC"7;
"S \NAC"
BN"5"29;
%"TAP"
"1","(-5850,3250)","2","mstr_standard","I296";
;
CDS_LIB"mstr_standard"
BODY_TYPE"PLUMBING"
HDL_TAP"TRUE";
"B \NAC \NWC"8;
"S \NAC"
BN"2"35;
%"TAP"
"1","(-5850,3300)","2","mstr_standard","I297";
;
CDS_LIB"mstr_standard"
BODY_TYPE"PLUMBING"
HDL_TAP"TRUE";
"B \NAC \NWC"8;
"S \NAC"
BN"1"38;
%"TAP"
"1","(-5850,3200)","2","mstr_standard","I298";
;
CDS_LIB"mstr_standard"
BODY_TYPE"PLUMBING"
HDL_TAP"TRUE";
"B \NAC \NWC"8;
"S \NAC"
BN"3"32;
%"TAP"
"1","(-5850,3150)","2","mstr_standard","I299";
;
CDS_LIB"mstr_standard"
BODY_TYPE"PLUMBING"
HDL_TAP"TRUE";
"B \NAC \NWC"8;
"S \NAC"
BN"4"30;
%"TAP"
"1","(-5850,3100)","2","mstr_standard","I300";
;
CDS_LIB"mstr_standard"
BODY_TYPE"PLUMBING"
HDL_TAP"TRUE";
"B \NAC \NWC"8;
"S \NAC"
BN"5"28;
%"TAP"
"1","(-5850,3050)","2","mstr_standard","I301";
;
CDS_LIB"mstr_standard"
BODY_TYPE"PLUMBING"
HDL_TAP"TRUE";
"B \NAC \NWC"8;
"S \NAC"
BN"6"25;
%"Q_RES"
"1","(-6525,2050)","0","pure_quanta","I314";
;
LOCATION"R510"
$SEC"1"
CDS_SEC"1"
TOLERANCE"1%"
VALUE"15   "
PART_NUMBER"CS01502FB11"
PACK_TYPE"0402LF"
CDS_LIB"pure_quanta"
WATTAGE"1/16W"
MATERIAL"CHIP";
"B"
$PN"2"13;
"A"
$PN"1"11;
END.
